(kicad_pcb
	(version 20260206)
	(generator "pcbnew")
	(generator_version "10.0")
	(general
		(thickness 1.6)
		(legacy_teardrops no)
	)
	(paper "A4")
	(title_block
		(title "01162023_DA0F0TEBIF0_F0T_Expander_BD_F_brd_V02_OCP.brd")
		(comment 1 "Grand Teton / footprint 6619 of 9728 (PEX0), pads 834-954 of 2397")
	)
	(layers
		(0 "F.Cu" signal "TOP")
		(4 "In1.Cu" signal "GND")
		(6 "In2.Cu" signal "VCC")
		(8 "In3.Cu" signal "VCC1")
		(10 "In4.Cu" signal "GND1")
		(12 "In5.Cu" signal "IN1")
		(14 "In6.Cu" signal "GND2")
		(16 "In7.Cu" signal "IN2")
		(18 "In8.Cu" signal "GND3")
		(20 "In9.Cu" signal "IN3")
		(22 "In10.Cu" signal "GND4")
		(24 "In11.Cu" signal "IN4")
		(26 "In12.Cu" signal "GND5")
		(28 "In13.Cu" signal "IN5")
		(30 "In14.Cu" signal "GND6")
		(32 "In15.Cu" signal "IN6")
		(34 "In16.Cu" signal "GND7")
		(2 "B.Cu" signal "BOTTOM")
		(9 "F.Adhes" user "F.Adhesive")
		(11 "B.Adhes" user "B.Adhesive")
		(13 "F.Paste" user "Package Geometry/Pastemask Top")
		(15 "B.Paste" user "Package Geometry/Pastemask Bottom")
		(5 "F.SilkS" user "Ref Des/Silkscreen Top")
		(7 "B.SilkS" user "Ref Des/Silkscreen Bottom")
		(1 "F.Mask" user "Board Geometry/Soldermask Top")
		(3 "B.Mask" user "Board Geometry/Soldermask Bottom")
		(17 "Dwgs.User" user "User.Drawings")
		(19 "Cmts.User" user "User.Comments")
		(21 "Eco1.User" user "User.Eco1")
		(23 "Eco2.User" user "User.Eco2")
		(25 "Edge.Cuts" user "Board Geometry/Outline")
		(27 "Margin" user)
		(31 "F.CrtYd" user "Package Geometry/Place Bound Top")
		(29 "B.CrtYd" user "Package Geometry/Place Bound Bottom")
		(35 "F.Fab" user "Ref Des/Assembly Top")
		(33 "B.Fab" user "Ref Des/Assembly Bottom")
	)
	(footprint ""
		(layer "F.Cu")
		(at 59.649868 -295.89984)
		(property "Reference" "PEX0"
			(at -3.360166 35.566858 0)
			(unlocked yes)
			(layer "F.SilkS")
			(effects
				(font
					(size 2.032 1.524)
					(thickness 0.1524)
				)
				(justify left)
			)
		)
		(property "Value" ""
			(at 0 0 0)
			(layer "F.Fab")
			(effects
				(font
					(size 1.27 1.27)
				)
			)
		)
		(duplicate_pad_numbers_are_jumpers no)
		(pad "AU3" smd circle
			(at -20.899882 11.400028)
			(size 0.4572 0.4572)
			(layers "F.Cu" "F.Mask" "F.Paste")
			(net "Net_2713")
		)
		(pad "AU4" smd circle
			(at -19.949922 11.400028)
			(size 0.4572 0.4572)
			(layers "F.Cu" "F.Mask" "F.Paste")
			(net "Net_2727")
		)
		(pad "AU5" smd circle
			(at -18.999962 11.400028)
			(size 0.4572 0.4572)
			(layers "F.Cu" "F.Mask" "F.Paste")
			(net "GND")
		)
		(pad "AU6" smd circle
			(at -18.050002 11.400028)
			(size 0.4572 0.4572)
			(layers "F.Cu" "F.Mask" "F.Paste")
			(net "Net_2741")
		)
		(pad "AU7" smd circle
			(at -17.100042 11.400028)
			(size 0.4572 0.4572)
			(layers "F.Cu" "F.Mask" "F.Paste")
			(net "Net_2755")
		)
		(pad "AU8" smd circle
			(at -16.150082 11.400028)
			(size 0.4572 0.4572)
			(layers "F.Cu" "F.Mask" "F.Paste")
			(net "GND")
		)
		(pad "AU9" smd circle
			(at -15.200122 11.400028)
			(size 0.4572 0.4572)
			(layers "F.Cu" "F.Mask" "F.Paste")
			(net "GND")
		)
		(pad "AU10" smd circle
			(at -14.249908 11.400028)
			(size 0.4572 0.4572)
			(layers "F.Cu" "F.Mask" "F.Paste")
			(net "GND")
		)
		(pad "AU11" smd circle
			(at -13.299948 11.400028)
			(size 0.4572 0.4572)
			(layers "F.Cu" "F.Mask" "F.Paste")
			(net "GND")
		)
		(pad "AU12" smd circle
			(at -12.349988 11.400028)
			(size 0.4572 0.4572)
			(layers "F.Cu" "F.Mask" "F.Paste")
			(net "GND")
		)
		(pad "AU13" smd circle
			(at -11.400028 11.400028)
			(size 0.4572 0.4572)
			(layers "F.Cu" "F.Mask" "F.Paste")
			(net "GND")
		)
		(pad "AU14" smd circle
			(at -10.450068 11.400028)
			(size 0.4572 0.4572)
			(layers "F.Cu" "F.Mask" "F.Paste")
			(net "GND")
		)
		(pad "AU15" smd circle
			(at -9.500108 11.400028)
			(size 0.4572 0.4572)
			(layers "F.Cu" "F.Mask" "F.Paste")
			(net "GND")
		)
		(pad "AU16" smd circle
			(at -8.549894 11.400028)
			(size 0.4572 0.4572)
			(layers "F.Cu" "F.Mask" "F.Paste")
			(net "GND")
		)
		(pad "AU17" smd circle
			(at -7.599934 11.400028)
			(size 0.4572 0.4572)
			(layers "F.Cu" "F.Mask" "F.Paste")
			(net "GND")
		)
		(pad "AU18" smd circle
			(at -6.649974 11.400028)
			(size 0.4572 0.4572)
			(layers "F.Cu" "F.Mask" "F.Paste")
			(net "GND")
		)
		(pad "AU19" smd circle
			(at -5.700014 11.400028)
			(size 0.4572 0.4572)
			(layers "F.Cu" "F.Mask" "F.Paste")
			(net "GND")
		)
		(pad "AU20" smd circle
			(at -4.750054 11.400028)
			(size 0.4572 0.4572)
			(layers "F.Cu" "F.Mask" "F.Paste")
			(net "GND")
		)
		(pad "AU21" smd circle
			(at -3.800094 11.400028)
			(size 0.4572 0.4572)
			(layers "F.Cu" "F.Mask" "F.Paste")
			(net "GND")
		)
		(pad "AU22" smd circle
			(at -2.84988 11.400028)
			(size 0.4572 0.4572)
			(layers "F.Cu" "F.Mask" "F.Paste")
			(net "GND")
		)
		(pad "AU23" smd circle
			(at -1.89992 11.400028)
			(size 0.4572 0.4572)
			(layers "F.Cu" "F.Mask" "F.Paste")
			(net "GND")
		)
		(pad "AU24" smd circle
			(at -0.94996 11.400028)
			(size 0.4572 0.4572)
			(layers "F.Cu" "F.Mask" "F.Paste")
			(net "GND")
		)
		(pad "AU25" smd circle
			(at 0 11.400028)
			(size 0.4572 0.4572)
			(layers "F.Cu" "F.Mask" "F.Paste")
			(net "GND")
		)
		(pad "AU26" smd circle
			(at 0.94996 11.400028)
			(size 0.4572 0.4572)
			(layers "F.Cu" "F.Mask" "F.Paste")
			(net "GND")
		)
		(pad "AU27" smd circle
			(at 1.89992 11.400028)
			(size 0.4572 0.4572)
			(layers "F.Cu" "F.Mask" "F.Paste")
			(net "GND")
		)
		(pad "AU28" smd circle
			(at 2.84988 11.400028)
			(size 0.4572 0.4572)
			(layers "F.Cu" "F.Mask" "F.Paste")
			(net "GND")
		)
		(pad "AU29" smd circle
			(at 3.800094 11.400028)
			(size 0.4572 0.4572)
			(layers "F.Cu" "F.Mask" "F.Paste")
			(net "GND")
		)
		(pad "AU30" smd circle
			(at 4.750054 11.400028)
			(size 0.4572 0.4572)
			(layers "F.Cu" "F.Mask" "F.Paste")
			(net "GND")
		)
		(pad "AU31" smd circle
			(at 5.700014 11.400028)
			(size 0.4572 0.4572)
			(layers "F.Cu" "F.Mask" "F.Paste")
			(net "GND")
		)
		(pad "AU32" smd circle
			(at 6.649974 11.400028)
			(size 0.4572 0.4572)
			(layers "F.Cu" "F.Mask" "F.Paste")
			(net "GND")
		)
		(pad "AU33" smd circle
			(at 7.599934 11.400028)
			(size 0.4572 0.4572)
			(layers "F.Cu" "F.Mask" "F.Paste")
			(net "GND")
		)
		(pad "AU34" smd circle
			(at 8.549894 11.400028)
			(size 0.4572 0.4572)
			(layers "F.Cu" "F.Mask" "F.Paste")
			(net "GND")
		)
		(pad "AU35" smd circle
			(at 9.500108 11.400028)
			(size 0.4572 0.4572)
			(layers "F.Cu" "F.Mask" "F.Paste")
			(net "GND")
		)
		(pad "AU36" smd circle
			(at 10.450068 11.400028)
			(size 0.4572 0.4572)
			(layers "F.Cu" "F.Mask" "F.Paste")
			(net "GND")
		)
		(pad "AU37" smd circle
			(at 11.400028 11.400028)
			(size 0.4572 0.4572)
			(layers "F.Cu" "F.Mask" "F.Paste")
			(net "GND")
		)
		(pad "AU38" smd circle
			(at 12.349988 11.400028)
			(size 0.4572 0.4572)
			(layers "F.Cu" "F.Mask" "F.Paste")
			(net "Net_2876")
		)
		(pad "AU39" smd circle
			(at 13.299948 11.400028)
			(size 0.4572 0.4572)
			(layers "F.Cu" "F.Mask" "F.Paste")
			(net "Net_2848")
		)
		(pad "AU40" smd circle
			(at 14.249908 11.400028)
			(size 0.4572 0.4572)
			(layers "F.Cu" "F.Mask" "F.Paste")
			(net "GND")
		)
		(pad "AU41" smd circle
			(at 15.200122 11.400028)
			(size 0.4572 0.4572)
			(layers "F.Cu" "F.Mask" "F.Paste")
			(net "GND")
		)
		(pad "AU42" smd circle
			(at 16.150082 11.400028)
			(size 0.4572 0.4572)
			(layers "F.Cu" "F.Mask" "F.Paste")
			(net "GND")
		)
		(pad "AU43" smd circle
			(at 17.100042 11.400028)
			(size 0.4572 0.4572)
			(layers "F.Cu" "F.Mask" "F.Paste")
			(net "P5E_PEX0_STN0_TX_DP<4>")
		)
		(pad "AU44" smd circle
			(at 18.050002 11.400028)
			(size 0.4572 0.4572)
			(layers "F.Cu" "F.Mask" "F.Paste")
			(net "P5E_PEX0_STN0_TX_DN<4>")
		)
		(pad "AU45" smd circle
			(at 18.999962 11.400028)
			(size 0.4572 0.4572)
			(layers "F.Cu" "F.Mask" "F.Paste")
			(net "GND")
		)
		(pad "AU46" smd circle
			(at 19.949922 11.400028)
			(size 0.4572 0.4572)
			(layers "F.Cu" "F.Mask" "F.Paste")
			(net "P5E_PEX0_STN0_RX_DP<4>")
		)
		(pad "AU47" smd circle
			(at 20.899882 11.400028)
			(size 0.4572 0.4572)
			(layers "F.Cu" "F.Mask" "F.Paste")
			(net "P5E_PEX0_STN0_RX_DN<4>")
		)
		(pad "AU48" smd circle
			(at 21.850096 11.400028)
			(size 0.4572 0.4572)
			(layers "F.Cu" "F.Mask" "F.Paste")
			(net "GND")
		)
		(pad "AU49" smd circle
			(at 22.800056 11.400028)
			(size 0.4572 0.4572)
			(layers "F.Cu" "F.Mask" "F.Paste")
			(net "GND")
		)
		(pad "AV1" smd circle
			(at -22.800056 12.349988)
			(size 0.4572 0.4572)
			(layers "F.Cu" "F.Mask" "F.Paste")
			(net "Net_2714")
		)
		(pad "AV2" smd circle
			(at -21.850096 12.349988)
			(size 0.4572 0.4572)
			(layers "F.Cu" "F.Mask" "F.Paste")
			(net "Net_2728")
		)
		(pad "AV3" smd circle
			(at -20.899882 12.349988)
			(size 0.4572 0.4572)
			(layers "F.Cu" "F.Mask" "F.Paste")
			(net "GND")
		)
		(pad "AV4" smd circle
			(at -19.949922 12.349988)
			(size 0.4572 0.4572)
			(layers "F.Cu" "F.Mask" "F.Paste")
			(net "GND")
		)
		(pad "AV5" smd circle
			(at -18.999962 12.349988)
			(size 0.4572 0.4572)
			(layers "F.Cu" "F.Mask" "F.Paste")
			(net "GND")
		)
		(pad "AV6" smd circle
			(at -18.050002 12.349988)
			(size 0.4572 0.4572)
			(layers "F.Cu" "F.Mask" "F.Paste")
			(net "GND")
		)
		(pad "AV7" smd circle
			(at -17.100042 12.349988)
			(size 0.4572 0.4572)
			(layers "F.Cu" "F.Mask" "F.Paste")
			(net "GND")
		)
		(pad "AV8" smd circle
			(at -16.150082 12.349988)
			(size 0.4572 0.4572)
			(layers "F.Cu" "F.Mask" "F.Paste")
			(net "Net_2742")
		)
		(pad "AV9" smd circle
			(at -15.200122 12.349988)
			(size 0.4572 0.4572)
			(layers "F.Cu" "F.Mask" "F.Paste")
			(net "Net_2756")
		)
		(pad "AV10" smd circle
			(at -14.249908 12.349988)
			(size 0.4572 0.4572)
			(layers "F.Cu" "F.Mask" "F.Paste")
			(net "GND")
		)
		(pad "AV11" smd circle
			(at -13.299948 12.349988)
			(size 0.4572 0.4572)
			(layers "F.Cu" "F.Mask" "F.Paste")
			(net "GND")
		)
		(pad "AV12" smd circle
			(at -12.349988 12.349988)
			(size 0.4572 0.4572)
			(layers "F.Cu" "F.Mask" "F.Paste")
			(net "Net_2866")
		)
		(pad "AV13" smd circle
			(at -11.400028 12.349988)
			(size 0.4572 0.4572)
			(layers "F.Cu" "F.Mask" "F.Paste")
			(net "Net_2867")
		)
		(pad "AV14" smd circle
			(at -10.450068 12.349988)
			(size 0.4572 0.4572)
			(layers "F.Cu" "F.Mask" "F.Paste")
			(net "Net_2858")
		)
		(pad "AV15" smd circle
			(at -9.500108 12.349988)
			(size 0.4572 0.4572)
			(layers "F.Cu" "F.Mask" "F.Paste")
			(net "Net_2852")
		)
		(pad "AV16" smd circle
			(at -8.549894 12.349988)
			(size 0.4572 0.4572)
			(layers "F.Cu" "F.Mask" "F.Paste")
			(net "Net_2861")
		)
		(pad "AV17" smd circle
			(at -7.599934 12.349988)
			(size 0.4572 0.4572)
			(layers "F.Cu" "F.Mask" "F.Paste")
			(net "Net_2862")
		)
		(pad "AV18" smd circle
			(at -6.649974 12.349988)
			(size 0.4572 0.4572)
			(layers "F.Cu" "F.Mask" "F.Paste")
			(net "Net_2857")
		)
		(pad "AV19" smd circle
			(at -5.700014 12.349988)
			(size 0.4572 0.4572)
			(layers "F.Cu" "F.Mask" "F.Paste")
			(net "Net_2853")
		)
		(pad "AV20" smd circle
			(at -4.750054 12.349988)
			(size 0.4572 0.4572)
			(layers "F.Cu" "F.Mask" "F.Paste")
			(net "GND")
		)
		(pad "AV21" smd circle
			(at -3.800094 12.349988)
			(size 0.4572 0.4572)
			(layers "F.Cu" "F.Mask" "F.Paste")
			(net "Net_2892")
		)
		(pad "AV22" smd circle
			(at -2.84988 12.349988)
			(size 0.4572 0.4572)
			(layers "F.Cu" "F.Mask" "F.Paste")
			(net "Net_2893")
		)
		(pad "AV23" smd circle
			(at -1.89992 12.349988)
			(size 0.4572 0.4572)
			(layers "F.Cu" "F.Mask" "F.Paste")
			(net "Net_2895")
		)
		(pad "AV24" smd circle
			(at -0.94996 12.349988)
			(size 0.4572 0.4572)
			(layers "F.Cu" "F.Mask" "F.Paste")
			(net "GND")
		)
		(pad "AV25" smd circle
			(at 0 12.349988)
			(size 0.4572 0.4572)
			(layers "F.Cu" "F.Mask" "F.Paste")
			(net "PEX0_MODE_SEL2")
		)
		(pad "AV26" smd circle
			(at 0.94996 12.349988)
			(size 0.4572 0.4572)
			(layers "F.Cu" "F.Mask" "F.Paste")
			(net "PEX0_MODE_SEL7")
		)
		(pad "AV27" smd circle
			(at 1.89992 12.349988)
			(size 0.4572 0.4572)
			(layers "F.Cu" "F.Mask" "F.Paste")
			(net "PEX0_MODE_SEL3")
		)
		(pad "AV28" smd circle
			(at 2.84988 12.349988)
			(size 0.4572 0.4572)
			(layers "F.Cu" "F.Mask" "F.Paste")
			(net "PEX0_MODE_SEL9")
		)
		(pad "AV29" smd circle
			(at 3.800094 12.349988)
			(size 0.4572 0.4572)
			(layers "F.Cu" "F.Mask" "F.Paste")
			(net "PEX0_PCA9555_INT_R_N")
		)
		(pad "AV30" smd circle
			(at 4.750054 12.349988)
			(size 0.4572 0.4572)
			(layers "F.Cu" "F.Mask" "F.Paste")
			(net "PEX0_SYS_ERR_N")
		)
		(pad "AV31" smd circle
			(at 5.700014 12.349988)
			(size 0.4572 0.4572)
			(layers "F.Cu" "F.Mask" "F.Paste")
			(net "PEX0_MODE_SEL6")
		)
		(pad "AV32" smd circle
			(at 6.649974 12.349988)
			(size 0.4572 0.4572)
			(layers "F.Cu" "F.Mask" "F.Paste")
			(net "PEX0_MODE_SEL10")
		)
		(pad "AV33" smd circle
			(at 7.599934 12.349988)
			(size 0.4572 0.4572)
			(layers "F.Cu" "F.Mask" "F.Paste")
			(net "Net_2870")
		)
		(pad "AV34" smd circle
			(at 8.549894 12.349988)
			(size 0.4572 0.4572)
			(layers "F.Cu" "F.Mask" "F.Paste")
			(net "Net_2843")
		)
		(pad "AV35" smd circle
			(at 9.500108 12.349988)
			(size 0.4572 0.4572)
			(layers "F.Cu" "F.Mask" "F.Paste")
			(net "Net_2872")
		)
		(pad "AV36" smd circle
			(at 10.450068 12.349988)
			(size 0.4572 0.4572)
			(layers "F.Cu" "F.Mask" "F.Paste")
			(net "Net_2849")
		)
		(pad "AV37" smd circle
			(at 11.400028 12.349988)
			(size 0.4572 0.4572)
			(layers "F.Cu" "F.Mask" "F.Paste")
			(net "Net_2874")
		)
		(pad "AV38" smd circle
			(at 12.349988 12.349988)
			(size 0.4572 0.4572)
			(layers "F.Cu" "F.Mask" "F.Paste")
			(net "Net_2873")
		)
		(pad "AV39" smd circle
			(at 13.299948 12.349988)
			(size 0.4572 0.4572)
			(layers "F.Cu" "F.Mask" "F.Paste")
			(net "Net_2865")
		)
		(pad "AV40" smd circle
			(at 14.249908 12.349988)
			(size 0.4572 0.4572)
			(layers "F.Cu" "F.Mask" "F.Paste")
			(net "GND")
		)
		(pad "AV41" smd circle
			(at 15.200122 12.349988)
			(size 0.4572 0.4572)
			(layers "F.Cu" "F.Mask" "F.Paste")
			(net "P5E_PEX0_STN0_TX_DP<5>")
		)
		(pad "AV42" smd circle
			(at 16.150082 12.349988)
			(size 0.4572 0.4572)
			(layers "F.Cu" "F.Mask" "F.Paste")
			(net "P5E_PEX0_STN0_TX_DN<5>")
		)
		(pad "AV43" smd circle
			(at 17.100042 12.349988)
			(size 0.4572 0.4572)
			(layers "F.Cu" "F.Mask" "F.Paste")
			(net "GND")
		)
		(pad "AV44" smd circle
			(at 18.050002 12.349988)
			(size 0.4572 0.4572)
			(layers "F.Cu" "F.Mask" "F.Paste")
			(net "GND")
		)
		(pad "AV45" smd circle
			(at 18.999962 12.349988)
			(size 0.4572 0.4572)
			(layers "F.Cu" "F.Mask" "F.Paste")
			(net "GND")
		)
		(pad "AV46" smd circle
			(at 19.949922 12.349988)
			(size 0.4572 0.4572)
			(layers "F.Cu" "F.Mask" "F.Paste")
			(net "GND")
		)
		(pad "AV47" smd circle
			(at 20.899882 12.349988)
			(size 0.4572 0.4572)
			(layers "F.Cu" "F.Mask" "F.Paste")
			(net "GND")
		)
		(pad "AV48" smd circle
			(at 21.850096 12.349988)
			(size 0.4572 0.4572)
			(layers "F.Cu" "F.Mask" "F.Paste")
			(net "P5E_PEX0_STN0_RX_DP<5>")
		)
		(pad "AV49" smd circle
			(at 22.800056 12.349988)
			(size 0.4572 0.4572)
			(layers "F.Cu" "F.Mask" "F.Paste")
			(net "P5E_PEX0_STN0_RX_DN<5>")
		)
		(pad "AW1" smd circle
			(at -22.800056 13.299948)
			(size 0.4572 0.4572)
			(layers "F.Cu" "F.Mask" "F.Paste")
			(net "GND")
		)
		(pad "AW2" smd circle
			(at -21.850096 13.299948)
			(size 0.4572 0.4572)
			(layers "F.Cu" "F.Mask" "F.Paste")
			(net "GND")
		)
		(pad "AW3" smd circle
			(at -20.899882 13.299948)
			(size 0.4572 0.4572)
			(layers "F.Cu" "F.Mask" "F.Paste")
			(net "Net_2715")
		)
		(pad "AW4" smd circle
			(at -19.949922 13.299948)
			(size 0.4572 0.4572)
			(layers "F.Cu" "F.Mask" "F.Paste")
			(net "Net_2729")
		)
		(pad "AW5" smd circle
			(at -18.999962 13.299948)
			(size 0.4572 0.4572)
			(layers "F.Cu" "F.Mask" "F.Paste")
			(net "GND")
		)
		(pad "AW6" smd circle
			(at -18.050002 13.299948)
			(size 0.4572 0.4572)
			(layers "F.Cu" "F.Mask" "F.Paste")
			(net "Net_2743")
		)
		(pad "AW7" smd circle
			(at -17.100042 13.299948)
			(size 0.4572 0.4572)
			(layers "F.Cu" "F.Mask" "F.Paste")
			(net "Net_2757")
		)
		(pad "AW8" smd circle
			(at -16.150082 13.299948)
			(size 0.4572 0.4572)
			(layers "F.Cu" "F.Mask" "F.Paste")
			(net "GND")
		)
		(pad "AW9" smd circle
			(at -15.200122 13.299948)
			(size 0.4572 0.4572)
			(layers "F.Cu" "F.Mask" "F.Paste")
			(net "GND")
		)
		(pad "AW10" smd circle
			(at -14.249908 13.299948)
			(size 0.4572 0.4572)
			(layers "F.Cu" "F.Mask" "F.Paste")
			(net "GND")
		)
		(pad "AW11" smd circle
			(at -13.299948 13.299948)
			(size 0.4572 0.4572)
			(layers "F.Cu" "F.Mask" "F.Paste")
			(net "GND")
		)
		(pad "AW12" smd circle
			(at -12.349988 13.299948)
			(size 0.4572 0.4572)
			(layers "F.Cu" "F.Mask" "F.Paste")
			(net "Net_2864")
		)
		(pad "AW13" smd circle
			(at -11.400028 13.299948)
			(size 0.4572 0.4572)
			(layers "F.Cu" "F.Mask" "F.Paste")
			(net "Net_2860")
		)
		(pad "AW14" smd circle
			(at -10.450068 13.299948)
			(size 0.4572 0.4572)
			(layers "F.Cu" "F.Mask" "F.Paste")
			(net "Net_2856")
		)
		(pad "AW15" smd circle
			(at -9.500108 13.299948)
			(size 0.4572 0.4572)
			(layers "F.Cu" "F.Mask" "F.Paste")
			(net "Net_2851")
		)
		(pad "AW16" smd circle
			(at -8.549894 13.299948)
			(size 0.4572 0.4572)
			(layers "F.Cu" "F.Mask" "F.Paste")
			(net "Net_2863")
		)
		(pad "AW17" smd circle
			(at -7.599934 13.299948)
			(size 0.4572 0.4572)
			(layers "F.Cu" "F.Mask" "F.Paste")
			(net "Net_2859")
		)
		(pad "AW18" smd circle
			(at -6.649974 13.299948)
			(size 0.4572 0.4572)
			(layers "F.Cu" "F.Mask" "F.Paste")
			(net "Net_2855")
		)
		(pad "AW19" smd circle
			(at -5.700014 13.299948)
			(size 0.4572 0.4572)
			(layers "F.Cu" "F.Mask" "F.Paste")
			(net "Net_2850")
		)
		(pad "AW20" smd circle
			(at -4.750054 13.299948)
			(size 0.4572 0.4572)
			(layers "F.Cu" "F.Mask" "F.Paste")
			(net "GND")
		)
		(pad "AW21" smd circle
			(at -3.800094 13.299948)
			(size 0.4572 0.4572)
			(layers "F.Cu" "F.Mask" "F.Paste")
			(net "Net_2884")
		)
		(pad "AW22" smd circle
			(at -2.84988 13.299948)
			(size 0.4572 0.4572)
			(layers "F.Cu" "F.Mask" "F.Paste")
			(net "Net_2894")
		)
		(pad "AW23" smd circle
			(at -1.89992 13.299948)
			(size 0.4572 0.4572)
			(layers "F.Cu" "F.Mask" "F.Paste")
			(net "Net_2883")
		)
		(pad "AW24" smd circle
			(at -0.94996 13.299948)
			(size 0.4572 0.4572)
			(layers "F.Cu" "F.Mask" "F.Paste")
			(net "GND")
		)
		(pad "AW25" smd circle
			(at 0 13.299948)
			(size 0.4572 0.4572)
			(layers "F.Cu" "F.Mask" "F.Paste")
			(net "PEX0_MODE_SEL5")
		)
	)
)
